FILE_TYPE = CONNECTIVITY;
{Allegro Design Entry HDL 17.4-2019 S026 (4007227) 1/17/2022}
"PAGE_NUMBER" = 39;
0"NC";
1"M_C_CPU1_SA_DQ<31:0>";
2"M_C_CPU1_SB_DQ<31:0>";
3"M_C_CPU1_SA_CB<7:0>";
4"M_C_CPU1_SB_CB<7:0>";
5"M_C_CPU1_SA_DQS_DN<9:0>";
6"M_C_CPU1_SA_DQS_DP<9:0>";
7"M_C_CPU1_SB_DQS_DP<9:0>";
8"M_C_CPU1_SB_DQS_DN<9:0>";
9"M_C_CPU1_SA_CA<6:0>";
10"M_C_CPU1_SB_CA<6:0>";
11"M_C_CPU1_ALERT_N";
12"M_C_CPU1_ALERT_R_N";
13"TP_M_C_CPU1_SA_TEST39C";
14"M_C_CPU1_CLK_DN<0>";
15"M_C_CPU1_CLK_DP<0>";
16"M_C_CPU1_SA_CS_N<1>";
17"M_C_CPU1_SA_CS_N<0>";
18"M_C_CPU1_SA_RSP<0>";
19"M_C_CPU1_SA_PAR";
20"M_C_CPU1_SB_CS_N<0>";
21"M_C_CPU1_SB_CS_N<1>";
22"M_C_CPU1_SB_RSP<0>";
23"M_C_CPU1_SB_PAR";
24"M_C_CPU1_RESET_N";
25"M_C_CPU1_SB_CA<6>";
26"M_C_CPU1_SB_DQS_DN<9>";
27"M_C_CPU1_SA_CA<6>";
28"M_C_CPU1_SB_CA<5>";
29"M_C_CPU1_SA_CA<5>";
30"M_C_CPU1_SB_CA<4>";
31"M_C_CPU1_SA_CA<4>";
32"M_C_CPU1_SB_CA<3>";
33"M_C_CPU1_SA_CA<3>";
34"M_C_CPU1_SB_CA<2>";
35"M_C_CPU1_SA_CA<2>";
36"M_C_CPU1_SB_CA<1>";
37"M_C_CPU1_SA_CA<1>";
38"M_C_CPU1_SB_CA<0>";
39"M_C_CPU1_SA_CA<0>";
40"M_C_CPU1_SB_DQS_DP<9>";
41"M_C_CPU1_SB_DQS_DP<7>";
42"M_C_CPU1_SB_DQS_DP<6>";
43"M_C_CPU1_SB_DQS_DP<5>";
44"M_C_CPU1_SB_DQS_DP<4>";
45"M_C_CPU1_SB_DQS_DN<8>";
46"M_C_CPU1_SB_DQS_DP<3>";
47"M_C_CPU1_SB_DQS_DN<7>";
48"M_C_CPU1_SB_DQS_DP<2>";
49"M_C_CPU1_SB_DQS_DN<6>";
50"M_C_CPU1_SB_DQS_DP<1>";
51"M_C_CPU1_SB_DQS_DN<5>";
52"M_C_CPU1_SB_DQS_DP<0>";
53"M_C_CPU1_SB_DQS_DN<4>";
54"M_C_CPU1_SA_DQS_DN<9>";
55"M_C_CPU1_SB_DQS_DN<3>";
56"M_C_CPU1_SB_DQS_DN<2>";
57"M_C_CPU1_SB_DQS_DN<1>";
58"M_C_CPU1_SB_DQS_DN<0>";
59"M_C_CPU1_SB_DQS_DP<8>";
60"M_C_CPU1_SA_DQS_DN<0>";
61"M_C_CPU1_SA_DQS_DP<9>";
62"M_C_CPU1_SA_DQS_DP<8>";
63"M_C_CPU1_SA_DQS_DP<7>";
64"M_C_CPU1_SA_DQS_DP<6>";
65"M_C_CPU1_SA_DQS_DP<5>";
66"M_C_CPU1_SA_DQS_DP<4>";
67"M_C_CPU1_SA_DQS_DN<8>";
68"M_C_CPU1_SA_DQS_DP<3>";
69"M_C_CPU1_SA_DQS_DN<7>";
70"M_C_CPU1_SA_DQS_DP<2>";
71"M_C_CPU1_SA_DQS_DN<6>";
72"M_C_CPU1_SA_DQS_DP<1>";
73"M_C_CPU1_SA_DQS_DN<5>";
74"M_C_CPU1_SA_DQS_DP<0>";
75"M_C_CPU1_SA_DQS_DN<4>";
76"M_C_CPU1_SA_DQS_DN<3>";
77"M_C_CPU1_SA_DQS_DN<2>";
78"M_C_CPU1_SA_DQS_DN<1>";
79"M_C_CPU1_SB_CB<7>";
80"M_C_CPU1_SB_CB<6>";
81"M_C_CPU1_SB_CB<5>";
82"M_C_CPU1_SB_CB<4>";
83"M_C_CPU1_SB_CB<3>";
84"M_C_CPU1_SB_CB<2>";
85"M_C_CPU1_SB_CB<1>";
86"M_C_CPU1_SB_CB<0>";
87"M_C_CPU1_SA_CB<4>";
88"M_C_CPU1_SA_CB<3>";
89"M_C_CPU1_SA_CB<2>";
90"M_C_CPU1_SA_CB<1>";
91"M_C_CPU1_SA_CB<0>";
92"M_C_CPU1_SB_DQ<29>";
93"M_C_CPU1_SB_DQ<28>";
94"M_C_CPU1_SB_DQ<27>";
95"M_C_CPU1_SB_DQ<26>";
96"M_C_CPU1_SB_DQ<25>";
97"M_C_CPU1_SB_DQ<24>";
98"M_C_CPU1_SB_DQ<23>";
99"M_C_CPU1_SB_DQ<22>";
100"M_C_CPU1_SA_CB<7>";
101"M_C_CPU1_SA_CB<6>";
102"M_C_CPU1_SB_DQ<31>";
103"M_C_CPU1_SA_CB<5>";
104"M_C_CPU1_SB_DQ<30>";
105"M_C_CPU1_SB_DQ<7>";
106"M_C_CPU1_SB_DQ<6>";
107"M_C_CPU1_SB_DQ<5>";
108"M_C_CPU1_SB_DQ<4>";
109"M_C_CPU1_SB_DQ<19>";
110"M_C_CPU1_SB_DQ<18>";
111"M_C_CPU1_SB_DQ<17>";
112"M_C_CPU1_SB_DQ<16>";
113"M_C_CPU1_SB_DQ<15>";
114"M_C_CPU1_SB_DQ<14>";
115"M_C_CPU1_SB_DQ<13>";
116"M_C_CPU1_SB_DQ<12>";
117"M_C_CPU1_SB_DQ<11>";
118"M_C_CPU1_SB_DQ<10>";
119"M_C_CPU1_SB_DQ<21>";
120"M_C_CPU1_SB_DQ<9>";
121"M_C_CPU1_SB_DQ<20>";
122"M_C_CPU1_SB_DQ<8>";
123"M_C_CPU1_SA_DQ<24>";
124"M_C_CPU1_SA_DQ<23>";
125"M_C_CPU1_SA_DQ<22>";
126"M_C_CPU1_SA_DQ<21>";
127"M_C_CPU1_SA_DQ<20>";
128"M_C_CPU1_SA_DQ<31>";
129"M_C_CPU1_SB_DQ<3>";
130"M_C_CPU1_SA_DQ<30>";
131"M_C_CPU1_SB_DQ<2>";
132"M_C_CPU1_SB_DQ<1>";
133"M_C_CPU1_SB_DQ<0>";
134"M_C_CPU1_SA_DQ<19>";
135"M_C_CPU1_SA_DQ<18>";
136"M_C_CPU1_SA_DQ<29>";
137"M_C_CPU1_SA_DQ<17>";
138"M_C_CPU1_SA_DQ<28>";
139"M_C_CPU1_SA_DQ<27>";
140"M_C_CPU1_SA_DQ<26>";
141"M_C_CPU1_SA_DQ<25>";
142"M_C_CPU1_SA_DQ<8>";
143"M_C_CPU1_SA_DQ<13>";
144"M_C_CPU1_SA_DQ<7>";
145"M_C_CPU1_SA_DQ<12>";
146"M_C_CPU1_SA_DQ<6>";
147"M_C_CPU1_SA_DQ<11>";
148"M_C_CPU1_SA_DQ<5>";
149"M_C_CPU1_SA_DQ<10>";
150"M_C_CPU1_SA_DQ<4>";
151"M_C_CPU1_SA_DQ<3>";
152"M_C_CPU1_SA_DQ<2>";
153"M_C_CPU1_SA_DQ<1>";
154"M_C_CPU1_SA_DQ<0>";
155"M_C_CPU1_SA_DQ<16>";
156"M_C_CPU1_SA_DQ<15>";
157"M_C_CPU1_SA_DQ<9>";
158"M_C_CPU1_SA_DQ<14>";
%"GENOA_SP5"
"3","(-4750,3675)","0","pure_quanta","I159";
;
LOCATION"U26"
$SEC"3"
CDS_SEC"3"
PART_TYPE"SMLF"
MATERIAL"IO"
VALUE"SOCKET6096_13568-001"
CDS_LIB"pure_quanta"
CDS_LMAN_SYM_OUTLINE"-650,2525,650,-2525"
NEEDS_NO_SIZE"TRUE"
PART_NUMBER"DGA^6000030";
"TEST39C"
$PN"BF55"13;
"MC1_CLK_L"
$PN"BG57"0;
"MC1_CLK_H"
$PN"BF56"0;
"MC0_CLK_L"
$PN"BD56"14;
"MC0_CLK_H"
$PN"BC57"15;
"MCB_PAR"
$PN"BL57"23;
"MCA_PAR"
$PN"BC55"19;
"MCB_DQS_H9"
$PN"BV56"40;
"MCA_CHECK4"
$PN"AN57"87;
"MCA_DATA8"
$PN"L57"142;
"MCA_DATA13"
$PN"T55"143;
"MCA_DATA24"
$PN"AC57"123;
"MCA_DQS_L0"
$PN"H56"60;
"MCB0_CS_L0"
$PN"BM55"20;
"MCB1_CS_L0"
$PN"BL55"0;
"MCB_DATA7"
$PN"CH55"105;
"MCB_DQS_H7"
$PN"CV55"41;
"MCA_CHECK3"
$PN"AL55"88;
"MCA_DATA7"
$PN"L55"144;
"MCA_DATA12"
$PN"R57"145;
"MCA_DATA23"
$PN"AC55"124;
"MCB_DATA6"
$PN"CG57"106;
"MCB_DQS_H6"
$PN"CM55"42;
"MCA_CHECK2"
$PN"AK56"89;
"MCA_DATA6"
$PN"K56"146;
"MCA_DATA11"
$PN"N55"147;
"MCA_DATA22"
$PN"AB56"125;
"MCB_CA6"
$PN"BK56"25;
"MCB_DATA5"
$PN"CG55"107;
"MCB_DQS_H5"
$PN"CF55"43;
"MCB_DQS_L9"
$PN"BW57"26;
"MCA_CA6"
$PN"BB55"27;
"MCA_CHECK1"
$PN"AK55"90;
"MCA_DATA5"
$PN"K55"148;
"MCA_DATA10"
$PN"M56"149;
"MCA_DATA21"
$PN"AB55"126;
"MCB_CA5"
$PN"BK55"28;
"MCB_DATA4"
$PN"CF56"108;
"MCB_DQS_H4"
$PN"BY55"44;
"MCB_DQS_L8"
$PN"DC55"45;
"MCA_CA5"
$PN"BB56"29;
"MCA_CHECK0"
$PN"AJ57"91;
"MCA_DATA4"
$PN"J57"150;
"MCA_DATA20"
$PN"AA57"127;
"MCA_DATA31"
$PN"AJ55"128;
"MCA_DQS_H9"
$PN"AN55"61;
"MCB_CA4"
$PN"BJ55"30;
"MCB_DATA3"
$PN"CD55"129;
"MCB_DQS_H3"
$PN"DB56"46;
"MCB_DQS_L7"
$PN"CU55"47;
"MCA1_CS_L1"
$PN"AV55"0;
"MCA_CA4"
$PN"BA57"31;
"MCA_DATA3"
$PN"G55"151;
"MCA_DATA30"
$PN"AH56"130;
"MCA_DQS_H8"
$PN"AG55"62;
"MCB_CA3"
$PN"BJ57"32;
"MCB_DATA2"
$PN"CC57"131;
"MCB_DATA19"
$PN"CT55"109;
"MCB_DQS_H2"
$PN"CT56"48;
"MCB_DQS_L6"
$PN"CL55"49;
"MCA0_CS_L1"
$PN"AW55"16;
"MCA1_CS_L0"
$PN"AU57"0;
"MCA_CA3"
$PN"BA55"33;
"MCA_DATA2"
$PN"F56"152;
"MCA_DQS_H7"
$PN"AA55"63;
"MCB_CA2"
$PN"BH56"34;
"MCB_DATA1"
$PN"CC55"132;
"MCB_DATA18"
$PN"CR57"110;
"MCB_DATA29"
$PN"DE55"92;
"MCB_DQS_H1"
$PN"CK56"50;
"MCB_DQS_L5"
$PN"CE55"51;
"MCA0_CS_L0"
$PN"AV56"17;
"MCA_CA2"
$PN"AY55"35;
"MCA_DATA1"
$PN"F55"153;
"MCA_DQS_H6"
$PN"R55"64;
"MCB_CA1"
$PN"BH55"36;
"MCB_DATA0"
$PN"CB56"133;
"MCB_DATA17"
$PN"CR55"111;
"MCB_DATA28"
$PN"DD56"93;
"MCB_DQS_H0"
$PN"CD56"52;
"MCB_DQS_L4"
$PN"BW55"53;
"MCA_CA1"
$PN"AY56"37;
"MCA_DATA0"
$PN"E57"154;
"MCA_DQS_H5"
$PN"J55"65;
"MCA_DQS_L9"
$PN"AM55"54;
"MCB0_RSP_L"
$PN"BP56"22;
"MCB1_RSP_L"
$PN"BR57"0;
"MCB_CA0"
$PN"BG55"38;
"MCB_CHECK7"
$PN"BV55"79;
"MCB_DATA16"
$PN"CP56"112;
"MCB_DATA27"
$PN"DB55"94;
"MCB_DQS_L3"
$PN"DC57"55;
"MCA_CA0"
$PN"AW57"39;
"MCA_DQS_H4"
$PN"AL57"66;
"MCA_DQS_L8"
$PN"AF55"67;
"MCB_CHECK6"
$PN"BU57"80;
"MCB_DATA15"
$PN"CP55"113;
"MCB_DATA26"
$PN"DA57"95;
"MCB_DQS_L2"
$PN"CU57"56;
"MCA_DQS_H3"
$PN"AE57"68;
"MCA_DQS_L7"
$PN"Y55"69;
"MCB_CHECK5"
$PN"BU55"81;
"MCB_DATA14"
$PN"CN57"114;
"MCB_DATA25"
$PN"DA55"96;
"MCB_DQS_L1"
$PN"CL57"57;
"MCA_DATA19"
$PN"W55"134;
"MCA_DQS_H2"
$PN"W57"70;
"MCA_DQS_L6"
$PN"P55"71;
"MCB_CHECK4"
$PN"BT56"82;
"MCB_DATA13"
$PN"CN55"115;
"MCB_DATA24"
$PN"CY56"97;
"MCB_DQS_L0"
$PN"CE57"58;
"MCA_DATA18"
$PN"V56"135;
"MCA_DATA29"
$PN"AH55"136;
"MCA_DQS_H1"
$PN"N57"72;
"MCA_DQS_L5"
$PN"H55"73;
"MCB_CHECK3"
$PN"CB55"83;
"MCB_DATA12"
$PN"CM56"116;
"MCB_DATA23"
$PN"CY55"98;
"MCA_DATA17"
$PN"V55"137;
"MCA_DATA28"
$PN"AG57"138;
"MCA_DQS_H0"
$PN"G57"74;
"MCA_DQS_L4"
$PN"AM56"75;
"MCB_CHECK2"
$PN"CA57"84;
"MCB_DATA11"
$PN"CK55"117;
"MCB_DATA22"
$PN"CW57"99;
"MCA1_RSP_L"
$PN"BP55"0;
"MCA_CHECK7"
$PN"AR55"100;
"MCA_DATA16"
$PN"U57"155;
"MCA_DATA27"
$PN"AE55"139;
"MCA_DQS_L3"
$PN"AF56"76;
"MCB_CHECK1"
$PN"CA55"85;
"MCB_DATA10"
$PN"CJ57"118;
"MCB_DATA21"
$PN"CW55"119;
"MCA0_RSP_L"
$PN"BN55"18;
"MCA_CHECK6"
$PN"AP56"101;
"MCA_DATA15"
$PN"U55"156;
"MCA_DATA26"
$PN"AD56"140;
"MCA_DQS_L2"
$PN"Y56"77;
"MCB_CHECK0"
$PN"BY56"86;
"MCB_DATA9"
$PN"CJ55"120;
"MCB_DATA20"
$PN"CV56"121;
"MCB_DATA31"
$PN"DF55"102;
"MCA_CHECK5"
$PN"AP55"103;
"MCA_DATA9"
$PN"M55"157;
"MCA_DATA14"
$PN"T56"158;
"MCA_DATA25"
$PN"AD55"141;
"MCA_DQS_L1"
$PN"P56"78;
"MCB0_CS_L1"
$PN"BN57"21;
"MCB1_CS_L1"
$PN"BM56"0;
"MCB_DATA8"
$PN"CH56"122;
"MCB_DATA30"
$PN"DE57"104;
"MCB_DQS_H8"
$PN"DD55"59;
"MC_RESET_L"
$PN"AU55"24;
"MC_ALERT_L"
$PN"AT55"12;
%"TAP"
"1","(-3475,6050)","0","mstr_standard","I162";
;
CDS_LIB"mstr_standard"
BODY_TYPE"PLUMBING"
HDL_TAP"TRUE";
"B \NAC \NWC"1;
"S \NAC"
BN"0"154;
%"TAP"
"1","(-3475,6000)","0","mstr_standard","I163";
;
CDS_LIB"mstr_standard"
BODY_TYPE"PLUMBING"
HDL_TAP"TRUE";
"B \NAC \NWC"1;
"S \NAC"
BN"1"153;
%"TAP"
"1","(-3475,5900)","0","mstr_standard","I164";
;
CDS_LIB"mstr_standard"
BODY_TYPE"PLUMBING"
HDL_TAP"TRUE";
"B \NAC \NWC"1;
"S \NAC"
BN"3"151;
%"TAP"
"1","(-3475,5950)","0","mstr_standard","I165";
;
CDS_LIB"mstr_standard"
BODY_TYPE"PLUMBING"
HDL_TAP"TRUE";
"B \NAC \NWC"1;
"S \NAC"
BN"2"152;
%"TAP"
"1","(-3475,5750)","0","mstr_standard","I166";
;
CDS_LIB"mstr_standard"
BODY_TYPE"PLUMBING"
HDL_TAP"TRUE";
"B \NAC \NWC"1;
"S \NAC"
BN"6"146;
%"TAP"
"1","(-3475,5800)","0","mstr_standard","I167";
;
CDS_LIB"mstr_standard"
BODY_TYPE"PLUMBING"
HDL_TAP"TRUE";
"B \NAC \NWC"1;
"S \NAC"
BN"5"148;
%"TAP"
"1","(-3475,5850)","0","mstr_standard","I168";
;
CDS_LIB"mstr_standard"
BODY_TYPE"PLUMBING"
HDL_TAP"TRUE";
"B \NAC \NWC"1;
"S \NAC"
BN"4"150;
%"TAP"
"1","(-3475,5700)","0","mstr_standard","I169";
;
CDS_LIB"mstr_standard"
BODY_TYPE"PLUMBING"
HDL_TAP"TRUE";
"B \NAC \NWC"1;
"S \NAC"
BN"7"144;
%"TAP"
"1","(-3475,5550)","0","mstr_standard","I170";
;
CDS_LIB"mstr_standard"
BODY_TYPE"PLUMBING"
HDL_TAP"TRUE";
"B \NAC \NWC"1;
"S \NAC"
BN"9"157;
%"TAP"
"1","(-3475,5600)","0","mstr_standard","I171";
;
CDS_LIB"mstr_standard"
BODY_TYPE"PLUMBING"
HDL_TAP"TRUE";
"B \NAC \NWC"1;
"S \NAC"
BN"8"142;
%"TAP"
"1","(-3475,5500)","0","mstr_standard","I172";
;
CDS_LIB"mstr_standard"
BODY_TYPE"PLUMBING"
HDL_TAP"TRUE";
"B \NAC \NWC"1;
"S \NAC"
BN"10"149;
%"TAP"
"1","(-3475,5400)","0","mstr_standard","I173";
;
CDS_LIB"mstr_standard"
BODY_TYPE"PLUMBING"
HDL_TAP"TRUE";
"B \NAC \NWC"1;
"S \NAC"
BN"12"145;
%"TAP"
"1","(-3475,5450)","0","mstr_standard","I174";
;
CDS_LIB"mstr_standard"
BODY_TYPE"PLUMBING"
HDL_TAP"TRUE";
"B \NAC \NWC"1;
"S \NAC"
BN"11"147;
%"TAP"
"1","(-3475,5350)","0","mstr_standard","I175";
;
CDS_LIB"mstr_standard"
BODY_TYPE"PLUMBING"
HDL_TAP"TRUE";
"B \NAC \NWC"1;
"S \NAC"
BN"13"143;
%"TAP"
"1","(-3475,5300)","0","mstr_standard","I176";
;
CDS_LIB"mstr_standard"
BODY_TYPE"PLUMBING"
HDL_TAP"TRUE";
"B \NAC \NWC"1;
"S \NAC"
BN"14"158;
%"TAP"
"1","(-3475,5250)","0","mstr_standard","I177";
;
CDS_LIB"mstr_standard"
BODY_TYPE"PLUMBING"
HDL_TAP"TRUE";
"B \NAC \NWC"1;
"S \NAC"
BN"15"156;
%"TAP"
"1","(-3475,5150)","0","mstr_standard","I178";
;
CDS_LIB"mstr_standard"
BODY_TYPE"PLUMBING"
HDL_TAP"TRUE";
"B \NAC \NWC"1;
"S \NAC"
BN"16"155;
%"TAP"
"1","(-3475,5000)","0","mstr_standard","I179";
;
CDS_LIB"mstr_standard"
BODY_TYPE"PLUMBING"
HDL_TAP"TRUE";
"B \NAC \NWC"1;
"S \NAC"
BN"19"134;
%"TAP"
"1","(-3475,5050)","0","mstr_standard","I180";
;
CDS_LIB"mstr_standard"
BODY_TYPE"PLUMBING"
HDL_TAP"TRUE";
"B \NAC \NWC"1;
"S \NAC"
BN"18"135;
%"TAP"
"1","(-3475,5100)","0","mstr_standard","I181";
;
CDS_LIB"mstr_standard"
BODY_TYPE"PLUMBING"
HDL_TAP"TRUE";
"B \NAC \NWC"1;
"S \NAC"
BN"17"137;
%"TAP"
"1","(-3475,4900)","0","mstr_standard","I182";
;
CDS_LIB"mstr_standard"
BODY_TYPE"PLUMBING"
HDL_TAP"TRUE";
"B \NAC \NWC"1;
"S \NAC"
BN"21"126;
%"TAP"
"1","(-3475,4950)","0","mstr_standard","I183";
;
CDS_LIB"mstr_standard"
BODY_TYPE"PLUMBING"
HDL_TAP"TRUE";
"B \NAC \NWC"1;
"S \NAC"
BN"20"127;
%"TAP"
"1","(-3475,4800)","0","mstr_standard","I184";
;
CDS_LIB"mstr_standard"
BODY_TYPE"PLUMBING"
HDL_TAP"TRUE";
"B \NAC \NWC"1;
"S \NAC"
BN"23"124;
%"TAP"
"1","(-3475,4850)","0","mstr_standard","I185";
;
CDS_LIB"mstr_standard"
BODY_TYPE"PLUMBING"
HDL_TAP"TRUE";
"B \NAC \NWC"1;
"S \NAC"
BN"22"125;
%"TAP"
"1","(-3475,4650)","0","mstr_standard","I186";
;
CDS_LIB"mstr_standard"
BODY_TYPE"PLUMBING"
HDL_TAP"TRUE";
"B \NAC \NWC"1;
"S \NAC"
BN"25"141;
%"TAP"
"1","(-3475,4700)","0","mstr_standard","I187";
;
CDS_LIB"mstr_standard"
BODY_TYPE"PLUMBING"
HDL_TAP"TRUE";
"B \NAC \NWC"1;
"S \NAC"
BN"24"123;
%"TAP"
"1","(-3475,4600)","0","mstr_standard","I188";
;
CDS_LIB"mstr_standard"
BODY_TYPE"PLUMBING"
HDL_TAP"TRUE";
"B \NAC \NWC"1;
"S \NAC"
BN"26"140;
%"TAP"
"1","(-3475,4500)","0","mstr_standard","I189";
;
CDS_LIB"mstr_standard"
BODY_TYPE"PLUMBING"
HDL_TAP"TRUE";
"B \NAC \NWC"1;
"S \NAC"
BN"28"138;
%"TAP"
"1","(-3475,4550)","0","mstr_standard","I190";
;
CDS_LIB"mstr_standard"
BODY_TYPE"PLUMBING"
HDL_TAP"TRUE";
"B \NAC \NWC"1;
"S \NAC"
BN"27"139;
%"TAP"
"1","(-3475,4400)","0","mstr_standard","I191";
;
CDS_LIB"mstr_standard"
BODY_TYPE"PLUMBING"
HDL_TAP"TRUE";
"B \NAC \NWC"1;
"S \NAC"
BN"30"130;
%"TAP"
"1","(-3475,4450)","0","mstr_standard","I192";
;
CDS_LIB"mstr_standard"
BODY_TYPE"PLUMBING"
HDL_TAP"TRUE";
"B \NAC \NWC"1;
"S \NAC"
BN"29"136;
%"TAP"
"1","(-3475,4350)","0","mstr_standard","I193";
;
CDS_LIB"mstr_standard"
BODY_TYPE"PLUMBING"
HDL_TAP"TRUE";
"B \NAC \NWC"1;
"S \NAC"
BN"31"128;
%"TAP"
"1","(-3475,4250)","0","mstr_standard","I194";
;
CDS_LIB"mstr_standard"
BODY_TYPE"PLUMBING"
HDL_TAP"TRUE";
"B \NAC \NWC"2;
"S \NAC"
BN"0"133;
%"TAP"
"1","(-3475,4200)","0","mstr_standard","I195";
;
CDS_LIB"mstr_standard"
BODY_TYPE"PLUMBING"
HDL_TAP"TRUE";
"B \NAC \NWC"2;
"S \NAC"
BN"1"132;
%"TAP"
"1","(-3475,4100)","0","mstr_standard","I196";
;
CDS_LIB"mstr_standard"
BODY_TYPE"PLUMBING"
HDL_TAP"TRUE";
"B \NAC \NWC"2;
"S \NAC"
BN"3"129;
%"TAP"
"1","(-3475,4150)","0","mstr_standard","I197";
;
CDS_LIB"mstr_standard"
BODY_TYPE"PLUMBING"
HDL_TAP"TRUE";
"B \NAC \NWC"2;
"S \NAC"
BN"2"131;
%"TAP"
"1","(-3475,3950)","0","mstr_standard","I199";
;
CDS_LIB"mstr_standard"
BODY_TYPE"PLUMBING"
HDL_TAP"TRUE";
"B \NAC \NWC"2;
"S \NAC"
BN"6"106;
%"TAP"
"1","(-3475,4000)","0","mstr_standard","I200";
;
CDS_LIB"mstr_standard"
BODY_TYPE"PLUMBING"
HDL_TAP"TRUE";
"B \NAC \NWC"2;
"S \NAC"
BN"5"107;
%"TAP"
"1","(-3475,4050)","0","mstr_standard","I201";
;
CDS_LIB"mstr_standard"
BODY_TYPE"PLUMBING"
HDL_TAP"TRUE";
"B \NAC \NWC"2;
"S \NAC"
BN"4"108;
%"TAP"
"1","(-3475,3900)","0","mstr_standard","I202";
;
CDS_LIB"mstr_standard"
BODY_TYPE"PLUMBING"
HDL_TAP"TRUE";
"B \NAC \NWC"2;
"S \NAC"
BN"7"105;
%"TAP"
"1","(-3475,3750)","0","mstr_standard","I203";
;
CDS_LIB"mstr_standard"
BODY_TYPE"PLUMBING"
HDL_TAP"TRUE";
"B \NAC \NWC"2;
"S \NAC"
BN"9"120;
%"TAP"
"1","(-3475,3800)","0","mstr_standard","I204";
;
CDS_LIB"mstr_standard"
BODY_TYPE"PLUMBING"
HDL_TAP"TRUE";
"B \NAC \NWC"2;
"S \NAC"
BN"8"122;
%"TAP"
"1","(-3475,3700)","0","mstr_standard","I205";
;
CDS_LIB"mstr_standard"
BODY_TYPE"PLUMBING"
HDL_TAP"TRUE";
"B \NAC \NWC"2;
"S \NAC"
BN"10"118;
%"TAP"
"1","(-3475,3600)","0","mstr_standard","I206";
;
CDS_LIB"mstr_standard"
BODY_TYPE"PLUMBING"
HDL_TAP"TRUE";
"B \NAC \NWC"2;
"S \NAC"
BN"12"116;
%"TAP"
"1","(-3475,3650)","0","mstr_standard","I207";
;
CDS_LIB"mstr_standard"
BODY_TYPE"PLUMBING"
HDL_TAP"TRUE";
"B \NAC \NWC"2;
"S \NAC"
BN"11"117;
%"TAP"
"1","(-3475,3550)","0","mstr_standard","I208";
;
CDS_LIB"mstr_standard"
BODY_TYPE"PLUMBING"
HDL_TAP"TRUE";
"B \NAC \NWC"2;
"S \NAC"
BN"13"115;
%"TAP"
"1","(-3475,3450)","0","mstr_standard","I209";
;
CDS_LIB"mstr_standard"
BODY_TYPE"PLUMBING"
HDL_TAP"TRUE";
"B \NAC \NWC"2;
"S \NAC"
BN"15"113;
%"TAP"
"1","(-3475,3500)","0","mstr_standard","I210";
;
CDS_LIB"mstr_standard"
BODY_TYPE"PLUMBING"
HDL_TAP"TRUE";
"B \NAC \NWC"2;
"S \NAC"
BN"14"114;
%"TAP"
"1","(-3475,3350)","0","mstr_standard","I211";
;
CDS_LIB"mstr_standard"
BODY_TYPE"PLUMBING"
HDL_TAP"TRUE";
"B \NAC \NWC"2;
"S \NAC"
BN"16"112;
%"TAP"
"1","(-3475,3250)","0","mstr_standard","I212";
;
CDS_LIB"mstr_standard"
BODY_TYPE"PLUMBING"
HDL_TAP"TRUE";
"B \NAC \NWC"2;
"S \NAC"
BN"18"110;
%"TAP"
"1","(-3475,3300)","0","mstr_standard","I213";
;
CDS_LIB"mstr_standard"
BODY_TYPE"PLUMBING"
HDL_TAP"TRUE";
"B \NAC \NWC"2;
"S \NAC"
BN"17"111;
%"TAP"
"1","(-3475,3200)","0","mstr_standard","I214";
;
CDS_LIB"mstr_standard"
BODY_TYPE"PLUMBING"
HDL_TAP"TRUE";
"B \NAC \NWC"2;
"S \NAC"
BN"19"109;
%"TAP"
"1","(-3475,3100)","0","mstr_standard","I215";
;
CDS_LIB"mstr_standard"
BODY_TYPE"PLUMBING"
HDL_TAP"TRUE";
"B \NAC \NWC"2;
"S \NAC"
BN"21"119;
%"TAP"
"1","(-3475,3150)","0","mstr_standard","I216";
;
CDS_LIB"mstr_standard"
BODY_TYPE"PLUMBING"
HDL_TAP"TRUE";
"B \NAC \NWC"2;
"S \NAC"
BN"20"121;
%"TAP"
"1","(-3475,3050)","0","mstr_standard","I217";
;
CDS_LIB"mstr_standard"
BODY_TYPE"PLUMBING"
HDL_TAP"TRUE";
"B \NAC \NWC"2;
"S \NAC"
BN"22"99;
%"TAP"
"1","(-3475,2900)","0","mstr_standard","I218";
;
CDS_LIB"mstr_standard"
BODY_TYPE"PLUMBING"
HDL_TAP"TRUE";
"B \NAC \NWC"2;
"S \NAC"
BN"24"97;
%"TAP"
"1","(-3475,2850)","0","mstr_standard","I219";
;
CDS_LIB"mstr_standard"
BODY_TYPE"PLUMBING"
HDL_TAP"TRUE";
"B \NAC \NWC"2;
"S \NAC"
BN"25"96;
%"TAP"
"1","(-3475,3000)","0","mstr_standard","I220";
;
CDS_LIB"mstr_standard"
BODY_TYPE"PLUMBING"
HDL_TAP"TRUE";
"B \NAC \NWC"2;
"S \NAC"
BN"23"98;
%"TAP"
"1","(-3475,2750)","0","mstr_standard","I221";
;
CDS_LIB"mstr_standard"
BODY_TYPE"PLUMBING"
HDL_TAP"TRUE";
"B \NAC \NWC"2;
"S \NAC"
BN"27"94;
%"TAP"
"1","(-3475,2700)","0","mstr_standard","I222";
;
CDS_LIB"mstr_standard"
BODY_TYPE"PLUMBING"
HDL_TAP"TRUE";
"B \NAC \NWC"2;
"S \NAC"
BN"28"93;
%"TAP"
"1","(-3475,2800)","0","mstr_standard","I223";
;
CDS_LIB"mstr_standard"
BODY_TYPE"PLUMBING"
HDL_TAP"TRUE";
"B \NAC \NWC"2;
"S \NAC"
BN"26"95;
%"TAP"
"1","(-3475,2650)","0","mstr_standard","I224";
;
CDS_LIB"mstr_standard"
BODY_TYPE"PLUMBING"
HDL_TAP"TRUE";
"B \NAC \NWC"2;
"S \NAC"
BN"29"92;
%"TAP"
"1","(-3475,2600)","0","mstr_standard","I225";
;
CDS_LIB"mstr_standard"
BODY_TYPE"PLUMBING"
HDL_TAP"TRUE";
"B \NAC \NWC"2;
"S \NAC"
BN"30"104;
%"TAP"
"1","(-3475,2400)","0","mstr_standard","I226";
;
CDS_LIB"mstr_standard"
BODY_TYPE"PLUMBING"
HDL_TAP"TRUE";
"B \NAC \NWC"3;
"S \NAC"
BN"1"90;
%"TAP"
"1","(-3475,2350)","0","mstr_standard","I227";
;
CDS_LIB"mstr_standard"
BODY_TYPE"PLUMBING"
HDL_TAP"TRUE";
"B \NAC \NWC"3;
"S \NAC"
BN"2"89;
%"TAP"
"1","(-3475,2550)","0","mstr_standard","I228";
;
CDS_LIB"mstr_standard"
BODY_TYPE"PLUMBING"
HDL_TAP"TRUE";
"B \NAC \NWC"2;
"S \NAC"
BN"31"102;
%"TAP"
"1","(-3475,2450)","0","mstr_standard","I229";
;
CDS_LIB"mstr_standard"
BODY_TYPE"PLUMBING"
HDL_TAP"TRUE";
"B \NAC \NWC"3;
"S \NAC"
BN"0"91;
%"TAP"
"1","(-3475,2200)","0","mstr_standard","I230";
;
CDS_LIB"mstr_standard"
BODY_TYPE"PLUMBING"
HDL_TAP"TRUE";
"B \NAC \NWC"3;
"S \NAC"
BN"5"103;
%"TAP"
"1","(-3475,2250)","0","mstr_standard","I231";
;
CDS_LIB"mstr_standard"
BODY_TYPE"PLUMBING"
HDL_TAP"TRUE";
"B \NAC \NWC"3;
"S \NAC"
BN"4"87;
%"TAP"
"1","(-3475,2300)","0","mstr_standard","I232";
;
CDS_LIB"mstr_standard"
BODY_TYPE"PLUMBING"
HDL_TAP"TRUE";
"B \NAC \NWC"3;
"S \NAC"
BN"3"88;
%"TAP"
"1","(-3475,2150)","0","mstr_standard","I233";
;
CDS_LIB"mstr_standard"
BODY_TYPE"PLUMBING"
HDL_TAP"TRUE";
"B \NAC \NWC"3;
"S \NAC"
BN"6"101;
%"TAP"
"1","(-3475,2100)","0","mstr_standard","I234";
;
CDS_LIB"mstr_standard"
BODY_TYPE"PLUMBING"
HDL_TAP"TRUE";
"B \NAC \NWC"3;
"S \NAC"
BN"7"100;
%"TAP"
"1","(-3475,2000)","0","mstr_standard","I236";
;
CDS_LIB"mstr_standard"
BODY_TYPE"PLUMBING"
HDL_TAP"TRUE";
"B \NAC \NWC"4;
"S \NAC"
BN"0"86;
%"TAP"
"1","(-3475,1950)","0","mstr_standard","I237";
;
CDS_LIB"mstr_standard"
BODY_TYPE"PLUMBING"
HDL_TAP"TRUE";
"B \NAC \NWC"4;
"S \NAC"
BN"1"85;
%"TAP"
"1","(-3475,1900)","0","mstr_standard","I238";
;
CDS_LIB"mstr_standard"
BODY_TYPE"PLUMBING"
HDL_TAP"TRUE";
"B \NAC \NWC"4;
"S \NAC"
BN"2"84;
%"TAP"
"1","(-3475,1850)","0","mstr_standard","I239";
;
CDS_LIB"mstr_standard"
BODY_TYPE"PLUMBING"
HDL_TAP"TRUE";
"B \NAC \NWC"4;
"S \NAC"
BN"3"83;
%"TAP"
"1","(-3475,1800)","0","mstr_standard","I240";
;
CDS_LIB"mstr_standard"
BODY_TYPE"PLUMBING"
HDL_TAP"TRUE";
"B \NAC \NWC"4;
"S \NAC"
BN"4"82;
%"TAP"
"1","(-3475,1750)","0","mstr_standard","I241";
;
CDS_LIB"mstr_standard"
BODY_TYPE"PLUMBING"
HDL_TAP"TRUE";
"B \NAC \NWC"4;
"S \NAC"
BN"5"81;
%"TAP"
"1","(-3475,1650)","0","mstr_standard","I242";
;
CDS_LIB"mstr_standard"
BODY_TYPE"PLUMBING"
HDL_TAP"TRUE";
"B \NAC \NWC"4;
"S \NAC"
BN"7"79;
%"TAP"
"1","(-3475,1700)","0","mstr_standard","I243";
;
CDS_LIB"mstr_standard"
BODY_TYPE"PLUMBING"
HDL_TAP"TRUE";
"B \NAC \NWC"4;
"S \NAC"
BN"6"80;
%"TAP"
"1","(-5900,6050)","2","mstr_standard","I244";
;
CDS_LIB"mstr_standard"
BODY_TYPE"PLUMBING"
HDL_TAP"TRUE";
"B \NAC \NWC"6;
"S \NAC"
BN"0"74;
%"TAP"
"1","(-5900,5950)","2","mstr_standard","I245";
;
CDS_LIB"mstr_standard"
BODY_TYPE"PLUMBING"
HDL_TAP"TRUE";
"B \NAC \NWC"6;
"S \NAC"
BN"1"72;
%"TAP"
"1","(-5900,5850)","2","mstr_standard","I246";
;
CDS_LIB"mstr_standard"
BODY_TYPE"PLUMBING"
HDL_TAP"TRUE";
"B \NAC \NWC"6;
"S \NAC"
BN"2"70;
%"TAP"
"1","(-5900,5650)","2","mstr_standard","I247";
;
CDS_LIB"mstr_standard"
BODY_TYPE"PLUMBING"
HDL_TAP"TRUE";
"B \NAC \NWC"6;
"S \NAC"
BN"4"66;
%"TAP"
"1","(-5900,5750)","2","mstr_standard","I248";
;
CDS_LIB"mstr_standard"
BODY_TYPE"PLUMBING"
HDL_TAP"TRUE";
"B \NAC \NWC"6;
"S \NAC"
BN"3"68;
%"TAP"
"1","(-6100,5900)","2","mstr_standard","I249";
;
CDS_LIB"mstr_standard"
BODY_TYPE"PLUMBING"
HDL_TAP"TRUE";
"B \NAC \NWC"5;
"S \NAC"
BN"1"78;
%"TAP"
"1","(-6100,6000)","2","mstr_standard","I250";
;
CDS_LIB"mstr_standard"
BODY_TYPE"PLUMBING"
HDL_TAP"TRUE";
"B \NAC \NWC"5;
"S \NAC"
BN"0"60;
%"TAP"
"1","(-6100,5800)","2","mstr_standard","I251";
;
CDS_LIB"mstr_standard"
BODY_TYPE"PLUMBING"
HDL_TAP"TRUE";
"B \NAC \NWC"5;
"S \NAC"
BN"2"77;
%"TAP"
"1","(-6100,5700)","2","mstr_standard","I252";
;
CDS_LIB"mstr_standard"
BODY_TYPE"PLUMBING"
HDL_TAP"TRUE";
"B \NAC \NWC"5;
"S \NAC"
BN"3"76;
%"TAP"
"1","(-5900,5550)","2","mstr_standard","I253";
;
CDS_LIB"mstr_standard"
BODY_TYPE"PLUMBING"
HDL_TAP"TRUE";
"B \NAC \NWC"6;
"S \NAC"
BN"5"65;
%"TAP"
"1","(-5900,5450)","2","mstr_standard","I254";
;
CDS_LIB"mstr_standard"
BODY_TYPE"PLUMBING"
HDL_TAP"TRUE";
"B \NAC \NWC"6;
"S \NAC"
BN"6"64;
%"TAP"
"1","(-5900,5250)","2","mstr_standard","I255";
;
CDS_LIB"mstr_standard"
BODY_TYPE"PLUMBING"
HDL_TAP"TRUE";
"B \NAC \NWC"6;
"S \NAC"
BN"8"62;
%"TAP"
"1","(-5900,5350)","2","mstr_standard","I256";
;
CDS_LIB"mstr_standard"
BODY_TYPE"PLUMBING"
HDL_TAP"TRUE";
"B \NAC \NWC"6;
"S \NAC"
BN"7"63;
%"TAP"
"1","(-5900,5150)","2","mstr_standard","I257";
;
CDS_LIB"mstr_standard"
BODY_TYPE"PLUMBING"
HDL_TAP"TRUE";
"B \NAC \NWC"6;
"S \NAC"
BN"9"61;
%"TAP"
"1","(-6100,5500)","2","mstr_standard","I258";
;
CDS_LIB"mstr_standard"
BODY_TYPE"PLUMBING"
HDL_TAP"TRUE";
"B \NAC \NWC"5;
"S \NAC"
BN"5"73;
%"TAP"
"1","(-6100,5600)","2","mstr_standard","I259";
;
CDS_LIB"mstr_standard"
BODY_TYPE"PLUMBING"
HDL_TAP"TRUE";
"B \NAC \NWC"5;
"S \NAC"
BN"4"75;
%"TAP"
"1","(-6100,5400)","2","mstr_standard","I260";
;
CDS_LIB"mstr_standard"
BODY_TYPE"PLUMBING"
HDL_TAP"TRUE";
"B \NAC \NWC"5;
"S \NAC"
BN"6"71;
%"TAP"
"1","(-6100,5300)","2","mstr_standard","I261";
;
CDS_LIB"mstr_standard"
BODY_TYPE"PLUMBING"
HDL_TAP"TRUE";
"B \NAC \NWC"5;
"S \NAC"
BN"7"69;
%"TAP"
"1","(-6100,5200)","2","mstr_standard","I262";
;
CDS_LIB"mstr_standard"
BODY_TYPE"PLUMBING"
HDL_TAP"TRUE";
"B \NAC \NWC"5;
"S \NAC"
BN"8"67;
%"TAP"
"1","(-5900,5000)","2","mstr_standard","I263";
;
CDS_LIB"mstr_standard"
BODY_TYPE"PLUMBING"
HDL_TAP"TRUE";
"B \NAC \NWC"7;
"S \NAC"
BN"0"52;
%"TAP"
"1","(-5900,4900)","2","mstr_standard","I264";
;
CDS_LIB"mstr_standard"
BODY_TYPE"PLUMBING"
HDL_TAP"TRUE";
"B \NAC \NWC"7;
"S \NAC"
BN"1"50;
%"TAP"
"1","(-5900,4800)","2","mstr_standard","I265";
;
CDS_LIB"mstr_standard"
BODY_TYPE"PLUMBING"
HDL_TAP"TRUE";
"B \NAC \NWC"7;
"S \NAC"
BN"2"48;
%"TAP"
"1","(-5900,4700)","2","mstr_standard","I266";
;
CDS_LIB"mstr_standard"
BODY_TYPE"PLUMBING"
HDL_TAP"TRUE";
"B \NAC \NWC"7;
"S \NAC"
BN"3"46;
%"TAP"
"1","(-6100,5100)","2","mstr_standard","I267";
;
CDS_LIB"mstr_standard"
BODY_TYPE"PLUMBING"
HDL_TAP"TRUE";
"B \NAC \NWC"5;
"S \NAC"
BN"9"54;
%"TAP"
"1","(-6100,4950)","2","mstr_standard","I268";
;
CDS_LIB"mstr_standard"
BODY_TYPE"PLUMBING"
HDL_TAP"TRUE";
"B \NAC \NWC"8;
"S \NAC"
BN"0"58;
%"TAP"
"1","(-6100,4850)","2","mstr_standard","I269";
;
CDS_LIB"mstr_standard"
BODY_TYPE"PLUMBING"
HDL_TAP"TRUE";
"B \NAC \NWC"8;
"S \NAC"
BN"1"57;
%"TAP"
"1","(-6100,4750)","2","mstr_standard","I270";
;
CDS_LIB"mstr_standard"
BODY_TYPE"PLUMBING"
HDL_TAP"TRUE";
"B \NAC \NWC"8;
"S \NAC"
BN"2"56;
%"TAP"
"1","(-6100,4650)","2","mstr_standard","I271";
;
CDS_LIB"mstr_standard"
BODY_TYPE"PLUMBING"
HDL_TAP"TRUE";
"B \NAC \NWC"8;
"S \NAC"
BN"3"55;
%"TAP"
"1","(-5900,4500)","2","mstr_standard","I272";
;
CDS_LIB"mstr_standard"
BODY_TYPE"PLUMBING"
HDL_TAP"TRUE";
"B \NAC \NWC"7;
"S \NAC"
BN"5"43;
%"TAP"
"1","(-5900,4600)","2","mstr_standard","I273";
;
CDS_LIB"mstr_standard"
BODY_TYPE"PLUMBING"
HDL_TAP"TRUE";
"B \NAC \NWC"7;
"S \NAC"
BN"4"44;
%"TAP"
"1","(-5900,4400)","2","mstr_standard","I274";
;
CDS_LIB"mstr_standard"
BODY_TYPE"PLUMBING"
HDL_TAP"TRUE";
"B \NAC \NWC"7;
"S \NAC"
BN"6"42;
%"TAP"
"1","(-5900,4300)","2","mstr_standard","I275";
;
CDS_LIB"mstr_standard"
BODY_TYPE"PLUMBING"
HDL_TAP"TRUE";
"B \NAC \NWC"7;
"S \NAC"
BN"7"41;
%"TAP"
"1","(-5900,4100)","2","mstr_standard","I276";
;
CDS_LIB"mstr_standard"
BODY_TYPE"PLUMBING"
HDL_TAP"TRUE";
"B \NAC \NWC"7;
"S \NAC"
BN"9"40;
%"TAP"
"1","(-5900,4200)","2","mstr_standard","I277";
;
CDS_LIB"mstr_standard"
BODY_TYPE"PLUMBING"
HDL_TAP"TRUE";
"B \NAC \NWC"7;
"S \NAC"
BN"8"59;
%"TAP"
"1","(-6100,4450)","2","mstr_standard","I278";
;
CDS_LIB"mstr_standard"
BODY_TYPE"PLUMBING"
HDL_TAP"TRUE";
"B \NAC \NWC"8;
"S \NAC"
BN"5"51;
%"TAP"
"1","(-6100,4550)","2","mstr_standard","I279";
;
CDS_LIB"mstr_standard"
BODY_TYPE"PLUMBING"
HDL_TAP"TRUE";
"B \NAC \NWC"8;
"S \NAC"
BN"4"53;
%"TAP"
"1","(-6100,4350)","2","mstr_standard","I280";
;
CDS_LIB"mstr_standard"
BODY_TYPE"PLUMBING"
HDL_TAP"TRUE";
"B \NAC \NWC"8;
"S \NAC"
BN"6"49;
%"TAP"
"1","(-6100,4250)","2","mstr_standard","I281";
;
CDS_LIB"mstr_standard"
BODY_TYPE"PLUMBING"
HDL_TAP"TRUE";
"B \NAC \NWC"8;
"S \NAC"
BN"7"47;
%"TAP"
"1","(-6100,4150)","2","mstr_standard","I282";
;
CDS_LIB"mstr_standard"
BODY_TYPE"PLUMBING"
HDL_TAP"TRUE";
"B \NAC \NWC"8;
"S \NAC"
BN"8"45;
%"TAP"
"1","(-6100,4050)","2","mstr_standard","I287";
;
CDS_LIB"mstr_standard"
BODY_TYPE"PLUMBING"
HDL_TAP"TRUE";
"B \NAC \NWC"8;
"S \NAC"
BN"9"26;
%"TAP"
"1","(-6100,3850)","2","mstr_standard","I288";
;
CDS_LIB"mstr_standard"
BODY_TYPE"PLUMBING"
HDL_TAP"TRUE";
"B \NAC \NWC"9;
"S \NAC"
BN"1"37;
%"TAP"
"1","(-6100,3900)","2","mstr_standard","I289";
;
CDS_LIB"mstr_standard"
BODY_TYPE"PLUMBING"
HDL_TAP"TRUE";
"B \NAC \NWC"9;
"S \NAC"
BN"0"39;
%"TAP"
"1","(-6100,3750)","2","mstr_standard","I290";
;
CDS_LIB"mstr_standard"
BODY_TYPE"PLUMBING"
HDL_TAP"TRUE";
"B \NAC \NWC"9;
"S \NAC"
BN"3"33;
%"TAP"
"1","(-6100,3800)","2","mstr_standard","I291";
;
CDS_LIB"mstr_standard"
BODY_TYPE"PLUMBING"
HDL_TAP"TRUE";
"B \NAC \NWC"9;
"S \NAC"
BN"2"35;
%"TAP"
"1","(-6100,3700)","2","mstr_standard","I292";
;
CDS_LIB"mstr_standard"
BODY_TYPE"PLUMBING"
HDL_TAP"TRUE";
"B \NAC \NWC"9;
"S \NAC"
BN"4"31;
%"TAP"
"1","(-6100,3650)","2","mstr_standard","I293";
;
CDS_LIB"mstr_standard"
BODY_TYPE"PLUMBING"
HDL_TAP"TRUE";
"B \NAC \NWC"9;
"S \NAC"
BN"5"29;
%"TAP"
"1","(-6100,3600)","2","mstr_standard","I294";
;
CDS_LIB"mstr_standard"
BODY_TYPE"PLUMBING"
HDL_TAP"TRUE";
"B \NAC \NWC"9;
"S \NAC"
BN"6"27;
%"TAP"
"1","(-6100,3400)","2","mstr_standard","I295";
;
CDS_LIB"mstr_standard"
BODY_TYPE"PLUMBING"
HDL_TAP"TRUE";
"B \NAC \NWC"10;
"S \NAC"
BN"2"34;
%"TAP"
"1","(-6100,3450)","2","mstr_standard","I296";
;
CDS_LIB"mstr_standard"
BODY_TYPE"PLUMBING"
HDL_TAP"TRUE";
"B \NAC \NWC"10;
"S \NAC"
BN"1"36;
%"TAP"
"1","(-6100,3500)","2","mstr_standard","I297";
;
CDS_LIB"mstr_standard"
BODY_TYPE"PLUMBING"
HDL_TAP"TRUE";
"B \NAC \NWC"10;
"S \NAC"
BN"0"38;
%"TAP"
"1","(-6100,3350)","2","mstr_standard","I298";
;
CDS_LIB"mstr_standard"
BODY_TYPE"PLUMBING"
HDL_TAP"TRUE";
"B \NAC \NWC"10;
"S \NAC"
BN"3"32;
%"TAP"
"1","(-6100,3300)","2","mstr_standard","I299";
;
CDS_LIB"mstr_standard"
BODY_TYPE"PLUMBING"
HDL_TAP"TRUE";
"B \NAC \NWC"10;
"S \NAC"
BN"4"30;
%"TAP"
"1","(-6100,3250)","2","mstr_standard","I300";
;
CDS_LIB"mstr_standard"
BODY_TYPE"PLUMBING"
HDL_TAP"TRUE";
"B \NAC \NWC"10;
"S \NAC"
BN"5"28;
%"TAP"
"1","(-6100,3200)","2","mstr_standard","I301";
;
CDS_LIB"mstr_standard"
BODY_TYPE"PLUMBING"
HDL_TAP"TRUE";
"B \NAC \NWC"10;
"S \NAC"
BN"6"25;
%"Q_RES"
"1","(-6775,2200)","0","pure_quanta","I313";
;
LOCATION"R502"
$SEC"1"
CDS_SEC"1"
PACK_TYPE"0402LF"
TOLERANCE"1%"
VALUE"15"
MATERIAL"CHIP"
WATTAGE"1/16W"
CDS_LIB"pure_quanta"
PART_NUMBER"CS01502FB03";
"B"
$PN"2"12;
"A"
$PN"1"11;
END.
